(kicad_pcb
	(version 20260206)
	(generator "pcbnew")
	(generator_version "10.0")
	(general
		(thickness 1.6)
		(legacy_teardrops no)
	)
	(paper "A4")
	(title_block
		(title "Bryce Canyon_F.DPB_16315-1-OCP.brd")
		(comment 1 "Bryce Canyon / footprints 1067-1074 of 2223")
	)
	(layers
		(0 "F.Cu" signal "TOP")
		(4 "In1.Cu" signal "L2GND")
		(6 "In2.Cu" signal "L3")
		(8 "In3.Cu" signal "L4GND")
		(10 "In4.Cu" signal "L5")
		(12 "In5.Cu" signal "L6VCC")
		(14 "In6.Cu" signal "L7VCC")
		(16 "In7.Cu" signal "L8")
		(18 "In8.Cu" signal "L9GND")
		(20 "In9.Cu" signal "L10")
		(22 "In10.Cu" signal "L11GND")
		(2 "B.Cu" signal "BOTTOM")
		(9 "F.Adhes" user "F.Adhesive")
		(11 "B.Adhes" user "B.Adhesive")
		(13 "F.Paste" user "Package Geometry/Pastemask Top")
		(15 "B.Paste" user "Package Geometry/Pastemask Bottom")
		(5 "F.SilkS" user "Ref Des/Silkscreen Top")
		(7 "B.SilkS" user "Ref Des/Silkscreen Bottom")
		(1 "F.Mask" user "Board Geometry/Soldermask Top")
		(3 "B.Mask" user "Board Geometry/Soldermask Bottom")
		(17 "Dwgs.User" user "User.Drawings")
		(19 "Cmts.User" user "User.Comments")
		(21 "Eco1.User" user "User.Eco1")
		(23 "Eco2.User" user "User.Eco2")
		(25 "Edge.Cuts" user "Board Geometry/Outline")
		(27 "Margin" user)
		(31 "F.CrtYd" user "Package Geometry/Place Bound Top")
		(29 "B.CrtYd" user "Package Geometry/Place Bound Bottom")
		(35 "F.Fab" user "Ref Des/Assembly Top")
		(33 "B.Fab" user "Ref Des/Assembly Bottom")
	)
	(footprint ""
		(layer "F.Cu")
		(at 86.121748 -274.846542 -90)
		(property "Reference" "R187"
			(at 0 0 270)
			(layer "F.SilkS")
			(hide yes)
			(effects
				(font
					(size 1.27 1.27)
				)
			)
		)
		(property "Value" "0R2J-2-GP"
			(at 0.064008 -3.993896 270)
			(unlocked yes)
			(layer "F.Fab")
			(hide yes)
			(effects
				(font
					(size 1.016 1.016)
					(thickness 0.1524)
				)
			)
		)
		(property "Device Type" "R402H16"
			(at 0.064008 -5.517896 270)
			(unlocked yes)
			(layer "F.Fab")
			(hide yes)
			(effects
				(font
					(size 1.016 1.016)
					(thickness 0.1524)
				)
			)
		)
		(duplicate_pad_numbers_are_jumpers no)
		(fp_line
			(start -0.508 -0.9398)
			(end -0.508 0.9398)
			(stroke
				(width 0.1524)
				(type default)
			)
			(layer "F.SilkS")
		)
		(fp_line
			(start 0.508 -0.9398)
			(end -0.508 -0.9398)
			(stroke
				(width 0.1524)
				(type default)
			)
			(layer "F.SilkS")
		)
		(fp_rect
			(start -0.508 0.9398)
			(end 0.508 -0.9398)
			(stroke
				(width 0)
				(type default)
			)
			(fill no)
			(layer "F.CrtYd")
		)
		(fp_rect
			(start -0.508 0.9398)
			(end 0.508 -0.9398)
			(stroke
				(width 0)
				(type default)
			)
			(fill no)
			(layer "F.Fab")
		)
		(pad "1" smd custom
			(at 0 -0.4445 270)
			(size 0.1397 0.1397)
			(layers "F.Cu" "F.Mask" "F.Paste")
			(net "DRIVE_A_2_PWR")
			(options
				(clearance outline)
				(anchor circle)
			)
			(primitives
				(gr_poly
					(pts
						(arc
							(start -0.1778 -0.2794)
							(mid -0.249642 -0.249642)
							(end -0.2794 -0.1778)
						)
						(arc
							(start -0.2794 0.1778)
							(mid -0.249642 0.249642)
							(end -0.1778 0.2794)
						)
						(arc
							(start 0.1778 0.2794)
							(mid 0.249642 0.249642)
							(end 0.2794 0.1778)
						)
						(arc
							(start 0.2794 -0.1778)
							(mid 0.249642 -0.249642)
							(end 0.1778 -0.2794)
						)
					)
					(width 0)
					(fill yes)
				)
			)
		)
		(pad "2" smd custom
			(at 0 0.4445 270)
			(size 0.1397 0.1397)
			(layers "F.Cu" "F.Mask" "F.Paste")
			(net "SW_PWR_R_HDD2")
			(options
				(clearance outline)
				(anchor circle)
			)
			(primitives
				(gr_poly
					(pts
						(arc
							(start -0.1778 -0.2794)
							(mid -0.249642 -0.249642)
							(end -0.2794 -0.1778)
						)
						(arc
							(start -0.2794 0.1778)
							(mid -0.249642 0.249642)
							(end -0.1778 0.2794)
						)
						(arc
							(start 0.1778 0.2794)
							(mid 0.249642 0.249642)
							(end 0.2794 0.1778)
						)
						(arc
							(start 0.2794 -0.1778)
							(mid 0.249642 -0.249642)
							(end 0.1778 -0.2794)
						)
					)
					(width 0)
					(fill yes)
				)
			)
		)
	)
	(footprint ""
		(layer "F.Cu")
		(at 475.530926 -177.778918 -90)
		(property "Reference" "C339"
			(at 0 0 270)
			(layer "F.SilkS")
			(hide yes)
			(effects
				(font
					(size 1.27 1.27)
				)
			)
		)
		(property "Value" "SC1U16V3KX-5GP"
			(at 0 -2.8194 270)
			(unlocked yes)
			(layer "F.Fab")
			(hide yes)
			(effects
				(font
					(size 1.016 1.016)
					(thickness 0.1524)
				)
			)
		)
		(property "Device Type" "C603H36"
			(at 0 -4.3434 270)
			(unlocked yes)
			(layer "F.Fab")
			(hide yes)
			(effects
				(font
					(size 1.016 1.016)
					(thickness 0.1524)
				)
			)
		)
		(duplicate_pad_numbers_are_jumpers no)
		(fp_line
			(start 0.508 0)
			(end -0.508 0)
			(stroke
				(width 0.2032)
				(type default)
			)
			(layer "F.SilkS")
		)
		(fp_rect
			(start -0.5842 1.3335)
			(end 0.5842 -1.3335)
			(stroke
				(width 0)
				(type default)
			)
			(fill no)
			(layer "F.CrtYd")
		)
		(fp_rect
			(start -0.5842 1.3335)
			(end 0.5842 -1.3335)
			(stroke
				(width 0)
				(type default)
			)
			(fill no)
			(layer "F.Fab")
		)
		(pad "1" smd custom
			(at 0 -0.762 270)
			(size 0.2159 0.2159)
			(layers "F.Cu" "F.Mask" "F.Paste")
			(net "P5V_HDD23")
			(options
				(clearance outline)
				(anchor circle)
			)
			(primitives
				(gr_poly
					(pts
						(arc
							(start -0.3302 -0.4318)
							(mid -0.402042 -0.402042)
							(end -0.4318 -0.3302)
						)
						(arc
							(start -0.4318 0.3302)
							(mid -0.402042 0.402042)
							(end -0.3302 0.4318)
						)
						(arc
							(start 0.3302 0.4318)
							(mid 0.402042 0.402042)
							(end 0.4318 0.3302)
						)
						(arc
							(start 0.4318 -0.3302)
							(mid 0.402042 -0.402042)
							(end 0.3302 -0.4318)
						)
					)
					(width 0)
					(fill yes)
				)
			)
		)
		(pad "2" smd custom
			(at 0 0.762 270)
			(size 0.2159 0.2159)
			(layers "F.Cu" "F.Mask" "F.Paste")
			(net "GND")
			(options
				(clearance outline)
				(anchor circle)
			)
			(primitives
				(gr_poly
					(pts
						(arc
							(start -0.3302 -0.4318)
							(mid -0.402042 -0.402042)
							(end -0.4318 -0.3302)
						)
						(arc
							(start -0.4318 0.3302)
							(mid -0.402042 0.402042)
							(end -0.3302 0.4318)
						)
						(arc
							(start 0.3302 0.4318)
							(mid 0.402042 0.402042)
							(end 0.4318 0.3302)
						)
						(arc
							(start 0.4318 -0.3302)
							(mid 0.402042 -0.402042)
							(end 0.3302 -0.4318)
						)
					)
					(width 0)
					(fill yes)
				)
			)
		)
	)
	(footprint ""
		(layer "F.Cu")
		(at 395.45895 -295.826942 180)
		(property "Reference" "C145"
			(at 0 0 180)
			(layer "F.SilkS")
			(hide yes)
			(effects
				(font
					(size 1.27 1.27)
				)
			)
		)
		(property "Value" "SC10U16V6KX-2GP"
			(at -0.0762 -5.1308 180)
			(unlocked yes)
			(layer "F.Fab")
			(hide yes)
			(effects
				(font
					(size 1.016 1.016)
					(thickness 0.1524)
				)
			)
		)
		(property "Device Type" "C1206H71"
			(at -0.127 -6.6548 180)
			(unlocked yes)
			(layer "F.Fab")
			(hide yes)
			(effects
				(font
					(size 1.016 1.016)
					(thickness 0.1524)
				)
			)
		)
		(duplicate_pad_numbers_are_jumpers no)
		(fp_line
			(start 1.016 2.2352)
			(end -1.016 2.2352)
			(stroke
				(width 0.1524)
				(type default)
			)
			(layer "F.SilkS")
		)
		(fp_line
			(start 1.016 0.8382)
			(end 1.016 2.2352)
			(stroke
				(width 0.1524)
				(type default)
			)
			(layer "F.SilkS")
		)
		(fp_line
			(start 1.016 -2.2352)
			(end 1.016 -0.8382)
			(stroke
				(width 0.1524)
				(type default)
			)
			(layer "F.SilkS")
		)
		(fp_line
			(start -1.016 2.2352)
			(end -1.016 0.8382)
			(stroke
				(width 0.1524)
				(type default)
			)
			(layer "F.SilkS")
		)
		(fp_line
			(start -1.016 -0.8382)
			(end -1.016 -2.2352)
			(stroke
				(width 0.1524)
				(type default)
			)
			(layer "F.SilkS")
		)
		(fp_line
			(start -1.016 -2.2352)
			(end 1.016 -2.2352)
			(stroke
				(width 0.1524)
				(type default)
			)
			(layer "F.SilkS")
		)
		(fp_rect
			(start -1.0922 2.3114)
			(end 1.0922 -2.3114)
			(stroke
				(width 0)
				(type default)
			)
			(fill no)
			(layer "F.CrtYd")
		)
		(fp_poly
			(pts
				(xy 1.0922 -2.3114) (xy 1.0922 2.3114) (xy -1.0922 2.3114) (xy -1.0922 -2.3114)
			)
			(stroke
				(width 0)
				(type default)
			)
			(fill no)
			(layer "F.Fab")
		)
		(pad "1" smd rect
			(at 0 -1.397 180)
			(size 1.651 1.27)
			(layers "F.Cu" "F.Mask" "F.Paste")
			(net "P5V_HDD8")
		)
		(pad "2" smd rect
			(at 0 1.397 180)
			(size 1.651 1.27)
			(layers "F.Cu" "F.Mask" "F.Paste")
			(net "GND")
		)
	)
	(footprint ""
		(layer "F.Cu")
		(at 267.18641 -133.312662 -90)
		(property "Reference" "TP186"
			(at 0 0 270)
			(layer "F.SilkS")
			(hide yes)
			(effects
				(font
					(size 1.27 1.27)
				)
			)
		)
		(property "Value" "TPAD32-GP"
			(at -0.0508 -1.6764 270)
			(unlocked yes)
			(layer "F.Fab")
			(hide yes)
			(effects
				(font
					(size 1.016 1.016)
					(thickness 0.1524)
				)
			)
		)
		(property "Device Type" "TPAD32"
			(at -0.0508 -3.2004 270)
			(unlocked yes)
			(layer "F.Fab")
			(hide yes)
			(effects
				(font
					(size 1.016 1.016)
					(thickness 0.1524)
				)
			)
		)
		(duplicate_pad_numbers_are_jumpers no)
		(fp_poly
			(pts
				(arc
					(start 0 -0.4064)
					(mid 0 0.4064)
					(end 0 -0.4064)
				)
			)
			(stroke
				(width 0)
				(type default)
			)
			(fill no)
			(layer "F.CrtYd")
		)
		(fp_poly
			(pts
				(arc
					(start 0 -0.7112)
					(mid 0 0.7112)
					(end 0 -0.7112)
				)
			)
			(stroke
				(width 0)
				(type default)
			)
			(fill no)
			(layer "F.Fab")
		)
		(pad "1" smd circle
			(at 0 0 270)
			(size 0.8128 0.8128)
			(layers "F.Cu" "F.Mask" "F.Paste")
			(net "TP_COMP_B_SATA_P0_RX_DN")
		)
	)
	(footprint ""
		(layer "F.Cu")
		(at 456.0189 -66.842894 180)
		(property "Reference" "C482"
			(at 0 0 180)
			(layer "F.SilkS")
			(hide yes)
			(effects
				(font
					(size 1.27 1.27)
				)
			)
		)
		(property "Value" "SC1U16V3KX-5GP"
			(at 0 -2.8194 180)
			(unlocked yes)
			(layer "F.Fab")
			(hide yes)
			(effects
				(font
					(size 1.016 1.016)
					(thickness 0.1524)
				)
			)
		)
		(property "Device Type" "C603H36"
			(at 0 -4.3434 180)
			(unlocked yes)
			(layer "F.Fab")
			(hide yes)
			(effects
				(font
					(size 1.016 1.016)
					(thickness 0.1524)
				)
			)
		)
		(duplicate_pad_numbers_are_jumpers no)
		(fp_line
			(start 0.508 0)
			(end -0.508 0)
			(stroke
				(width 0.2032)
				(type default)
			)
			(layer "F.SilkS")
		)
		(fp_rect
			(start -0.5842 1.3335)
			(end 0.5842 -1.3335)
			(stroke
				(width 0)
				(type default)
			)
			(fill no)
			(layer "F.CrtYd")
		)
		(fp_rect
			(start -0.5842 1.3335)
			(end 0.5842 -1.3335)
			(stroke
				(width 0)
				(type default)
			)
			(fill no)
			(layer "F.Fab")
		)
		(pad "1" smd custom
			(at 0 -0.762 180)
			(size 0.2159 0.2159)
			(layers "F.Cu" "F.Mask" "F.Paste")
			(net "P5V_HDD34")
			(options
				(clearance outline)
				(anchor circle)
			)
			(primitives
				(gr_poly
					(pts
						(arc
							(start -0.3302 -0.4318)
							(mid -0.402042 -0.402042)
							(end -0.4318 -0.3302)
						)
						(arc
							(start -0.4318 0.3302)
							(mid -0.402042 0.402042)
							(end -0.3302 0.4318)
						)
						(arc
							(start 0.3302 0.4318)
							(mid 0.402042 0.402042)
							(end 0.4318 0.3302)
						)
						(arc
							(start 0.4318 -0.3302)
							(mid 0.402042 -0.402042)
							(end 0.3302 -0.4318)
						)
					)
					(width 0)
					(fill yes)
				)
			)
		)
		(pad "2" smd custom
			(at 0 0.762 180)
			(size 0.2159 0.2159)
			(layers "F.Cu" "F.Mask" "F.Paste")
			(net "GND")
			(options
				(clearance outline)
				(anchor circle)
			)
			(primitives
				(gr_poly
					(pts
						(arc
							(start -0.3302 -0.4318)
							(mid -0.402042 -0.402042)
							(end -0.4318 -0.3302)
						)
						(arc
							(start -0.4318 0.3302)
							(mid -0.402042 0.402042)
							(end -0.3302 0.4318)
						)
						(arc
							(start 0.3302 0.4318)
							(mid 0.402042 0.402042)
							(end 0.4318 0.3302)
						)
						(arc
							(start 0.4318 -0.3302)
							(mid 0.402042 -0.402042)
							(end 0.3302 -0.4318)
						)
					)
					(width 0)
					(fill yes)
				)
			)
		)
	)
	(footprint ""
		(layer "F.Cu")
		(at 18.906998 -64.683894 90)
		(property "Reference" "R683"
			(at 0 0 90)
			(layer "F.SilkS")
			(hide yes)
			(effects
				(font
					(size 1.27 1.27)
				)
			)
		)
		(property "Value" "2R6F-GP"
			(at -0.0508 -4.8514 90)
			(unlocked yes)
			(layer "F.Fab")
			(hide yes)
			(effects
				(font
					(size 1.016 1.016)
					(thickness 0.1524)
				)
			)
		)
		(property "Device Type" "R1206H26"
			(at 0 -6.3754 90)
			(unlocked yes)
			(layer "F.Fab")
			(hide yes)
			(effects
				(font
					(size 1.016 1.016)
					(thickness 0.1524)
				)
			)
		)
		(duplicate_pad_numbers_are_jumpers no)
		(fp_line
			(start 1.016 -2.2352)
			(end 1.016 2.2352)
			(stroke
				(width 0.1524)
				(type default)
			)
			(layer "F.SilkS")
		)
		(fp_line
			(start -1.016 -2.2352)
			(end 1.016 -2.2352)
			(stroke
				(width 0.1524)
				(type default)
			)
			(layer "F.SilkS")
		)
		(fp_line
			(start 1.016 2.2352)
			(end -1.016 2.2352)
			(stroke
				(width 0.1524)
				(type default)
			)
			(layer "F.SilkS")
		)
		(fp_line
			(start -1.016 2.2352)
			(end -1.016 -2.2352)
			(stroke
				(width 0.1524)
				(type default)
			)
			(layer "F.SilkS")
		)
		(fp_rect
			(start -1.0922 2.3114)
			(end 1.0922 -2.3114)
			(stroke
				(width 0)
				(type default)
			)
			(fill no)
			(layer "F.CrtYd")
		)
		(fp_poly
			(pts
				(xy -1.0922 -2.3114) (xy 1.0922 -2.3114) (xy 1.0922 2.3114) (xy -1.0922 2.3114)
			)
			(stroke
				(width 0)
				(type default)
			)
			(fill no)
			(layer "F.Fab")
		)
		(pad "1" smd rect
			(at 0 -1.397 90)
			(size 1.651 1.27)
			(layers "F.Cu" "F.Mask" "F.Paste")
			(net "P12V_HDD24")
		)
		(pad "2" smd rect
			(at 0 1.397 90)
			(size 1.651 1.27)
			(layers "F.Cu" "F.Mask" "F.Paste")
			(net "12V_PRE_24")
		)
	)
	(footprint ""
		(layer "F.Cu")
		(at 146.247866 -131.656074)
		(property "Reference" "R1054"
			(at 0 0 0)
			(layer "F.SilkS")
			(hide yes)
			(effects
				(font
					(size 1.27 1.27)
				)
			)
		)
		(property "Value" "11KR2F-L-GP"
			(at 0.064008 -3.993896 0)
			(unlocked yes)
			(layer "F.Fab")
			(hide yes)
			(effects
				(font
					(size 1.016 1.016)
					(thickness 0.1524)
				)
			)
		)
		(property "Device Type" "R402H16"
			(at 0.064008 -5.517896 0)
			(unlocked yes)
			(layer "F.Fab")
			(hide yes)
			(effects
				(font
					(size 1.016 1.016)
					(thickness 0.1524)
				)
			)
		)
		(duplicate_pad_numbers_are_jumpers no)
		(fp_line
			(start -0.508 -0.9398)
			(end -0.508 0.9398)
			(stroke
				(width 0.1524)
				(type default)
			)
			(layer "F.SilkS")
		)
		(fp_line
			(start 0.508 -0.9398)
			(end -0.508 -0.9398)
			(stroke
				(width 0.1524)
				(type default)
			)
			(layer "F.SilkS")
		)
		(fp_rect
			(start -0.508 0.9398)
			(end 0.508 -0.9398)
			(stroke
				(width 0)
				(type default)
			)
			(fill no)
			(layer "F.CrtYd")
		)
		(fp_rect
			(start -0.508 0.9398)
			(end 0.508 -0.9398)
			(stroke
				(width 0)
				(type default)
			)
			(fill no)
			(layer "F.Fab")
		)
		(pad "1" smd custom
			(at 0 -0.4445)
			(size 0.1397 0.1397)
			(layers "F.Cu" "F.Mask" "F.Paste")
			(net "MB0_P12V_PWGIN_R")
			(options
				(clearance outline)
				(anchor circle)
			)
			(primitives
				(gr_poly
					(pts
						(arc
							(start -0.1778 -0.2794)
							(mid -0.249642 -0.249642)
							(end -0.2794 -0.1778)
						)
						(arc
							(start -0.2794 0.1778)
							(mid -0.249642 0.249642)
							(end -0.1778 0.2794)
						)
						(arc
							(start 0.1778 0.2794)
							(mid 0.249642 0.249642)
							(end 0.2794 0.1778)
						)
						(arc
							(start 0.2794 -0.1778)
							(mid 0.249642 -0.249642)
							(end 0.1778 -0.2794)
						)
					)
					(width 0)
					(fill yes)
				)
			)
		)
		(pad "2" smd custom
			(at 0 0.4445)
			(size 0.1397 0.1397)
			(layers "F.Cu" "F.Mask" "F.Paste")
			(net "AGND_CURRENT_MONOA")
			(options
				(clearance outline)
				(anchor circle)
			)
			(primitives
				(gr_poly
					(pts
						(arc
							(start -0.1778 -0.2794)
							(mid -0.249642 -0.249642)
							(end -0.2794 -0.1778)
						)
						(arc
							(start -0.2794 0.1778)
							(mid -0.249642 0.249642)
							(end -0.1778 0.2794)
						)
						(arc
							(start 0.1778 0.2794)
							(mid 0.249642 0.249642)
							(end 0.2794 0.1778)
						)
						(arc
							(start 0.2794 -0.1778)
							(mid 0.249642 -0.249642)
							(end 0.1778 -0.2794)
						)
					)
					(width 0)
					(fill yes)
				)
			)
		)
	)
	(footprint ""
		(layer "F.Cu")
		(at 364.290102 -163.554918 -90)
		(property "Reference" "R574"
			(at 0 0 270)
			(layer "F.SilkS")
			(hide yes)
			(effects
				(font
					(size 1.27 1.27)
				)
			)
		)
		(property "Value" "4K7R2J-2-GP"
			(at 0.064008 -3.993896 270)
			(unlocked yes)
			(layer "F.Fab")
			(hide yes)
			(effects
				(font
					(size 1.016 1.016)
					(thickness 0.1524)
				)
			)
		)
		(property "Device Type" "R402H16"
			(at 0.064008 -5.517896 270)
			(unlocked yes)
			(layer "F.Fab")
			(hide yes)
			(effects
				(font
					(size 1.016 1.016)
					(thickness 0.1524)
				)
			)
		)
		(duplicate_pad_numbers_are_jumpers no)
		(fp_line
			(start -0.508 -0.9398)
			(end -0.508 0.9398)
			(stroke
				(width 0.1524)
				(type default)
			)
			(layer "F.SilkS")
		)
		(fp_line
			(start 0.508 -0.9398)
			(end -0.508 -0.9398)
			(stroke
				(width 0.1524)
				(type default)
			)
			(layer "F.SilkS")
		)
		(fp_rect
			(start -0.508 0.9398)
			(end 0.508 -0.9398)
			(stroke
				(width 0)
				(type default)
			)
			(fill no)
			(layer "F.CrtYd")
		)
		(fp_rect
			(start -0.508 0.9398)
			(end 0.508 -0.9398)
			(stroke
				(width 0)
				(type default)
			)
			(fill no)
			(layer "F.Fab")
		)
		(pad "1" smd custom
			(at 0 -0.4445 270)
			(size 0.1397 0.1397)
			(layers "F.Cu" "F.Mask" "F.Paste")
			(net "P12V_A")
			(options
				(clearance outline)
				(anchor circle)
			)
			(primitives
				(gr_poly
					(pts
						(arc
							(start -0.1778 -0.2794)
							(mid -0.249642 -0.249642)
							(end -0.2794 -0.1778)
						)
						(arc
							(start -0.2794 0.1778)
							(mid -0.249642 0.249642)
							(end -0.1778 0.2794)
						)
						(arc
							(start 0.1778 0.2794)
							(mid 0.249642 0.249642)
							(end 0.2794 0.1778)
						)
						(arc
							(start 0.2794 -0.1778)
							(mid 0.249642 -0.249642)
							(end 0.1778 -0.2794)
						)
					)
					(width 0)
					(fill yes)
				)
			)
		)
		(pad "2" smd custom
			(at 0 0.4445 270)
			(size 0.1397 0.1397)
			(layers "F.Cu" "F.Mask" "F.Paste")
			(net "SW_HDD_P19")
			(options
				(clearance outline)
				(anchor circle)
			)
			(primitives
				(gr_poly
					(pts
						(arc
							(start -0.1778 -0.2794)
							(mid -0.249642 -0.249642)
							(end -0.2794 -0.1778)
						)
						(arc
							(start -0.2794 0.1778)
							(mid -0.249642 0.249642)
							(end -0.1778 0.2794)
						)
						(arc
							(start 0.1778 0.2794)
							(mid 0.249642 0.249642)
							(end 0.2794 0.1778)
						)
						(arc
							(start 0.2794 -0.1778)
							(mid 0.249642 -0.249642)
							(end 0.1778 -0.2794)
						)
					)
					(width 0)
					(fill yes)
				)
			)
		)
	)
)
